(kicad_pcb
	(version 20260206)
	(generator "pcbnew")
	(generator_version "10.0")
	(general
		(thickness 1.21888)
		(legacy_teardrops no)
	)
	(paper "A4")
	(title_block
		(title "timecard-v9 — TimeCard-DC-V9_EXP.PcbDoc")
		(comment 1 "Time Appliance Project (Time Card) / footprints 55-64 of 402")
	)
	(layers
		(0 "F.Cu" signal "TOP")
		(4 "In1.Cu" signal "SGND")
		(6 "In2.Cu" signal "IN1")
		(8 "In3.Cu" signal "IN2")
		(10 "In4.Cu" signal "SGND1")
		(2 "B.Cu" signal "BOTTOM")
		(9 "F.Adhes" user "F.Adhesive")
		(11 "B.Adhes" user "B.Adhesive")
		(13 "F.Paste" user "Top Paste")
		(15 "B.Paste" user "Bottom Paste")
		(5 "F.SilkS" user "Top Overlay")
		(7 "B.SilkS" user "Bottom Overlay")
		(1 "F.Mask" user "Top Solder")
		(3 "B.Mask" user "Bottom Solder")
		(17 "Dwgs.User" user "User.Drawings")
		(19 "Cmts.User" user "User.Comments")
		(21 "Eco1.User" user "User.Eco1")
		(23 "Eco2.User" user "User.Eco2")
		(25 "Edge.Cuts" user)
		(27 "Margin" user)
		(31 "F.CrtYd" user "Top Courtyard")
		(29 "B.CrtYd" user "Bottom Courtyard")
		(35 "F.Fab" user "Top Component Center")
		(33 "B.Fab" user "Bottom Component Center")
	)
	(footprint "Vault:RESC1608X55X25NL10T15"
		(layer "F.Cu")
		(at 75.0216 111.8162 90)
		(property "Reference" "R33"
			(at -0.3286 1.073069 270)
			(unlocked yes)
			(layer "F.SilkS")
			(effects
				(font
					(size 0.762 0.762)
					(thickness 0.2286)
				)
			)
		)
		(property "Value" "49.9R"
			(at -2.884671 3.186585 0)
			(unlocked yes)
			(layer "F.SilkS")
			(hide yes)
			(effects
				(font
					(size 0.762 0.762)
					(thickness 0.2286)
				)
			)
		)
		(sheetname "01-USER_IO")
		(sheetfile "01-USER_IO.kicad_sch")
		(duplicate_pad_numbers_are_jumpers no)
		(pad "1" smd rect
			(at -0.7 0 180)
			(size 0.9 0.7)
			(layers "F.Cu" "F.Mask" "F.Paste")
			(net "NetR33_1")
		)
		(pad "2" smd rect
			(at 0.7 0 180)
			(size 0.9 0.7)
			(layers "F.Cu" "F.Mask" "F.Paste")
			(net "NetAN2_1")
		)
	)
	(footprint "Vault:CAPC1608X87X45ML20T05"
		(layer "F.Cu")
		(at 105.46635 84.61749)
		(property "Reference" "C30"
			(at -0.5786 2.235469 180)
			(unlocked yes)
			(layer "F.SilkS")
			(effects
				(font
					(size 0.762 0.762)
					(thickness 0.2286)
				)
			)
		)
		(property "Value" "0.1uF"
			(at 2.069035 2.630671 0)
			(unlocked yes)
			(layer "F.SilkS")
			(hide yes)
			(effects
				(font
					(size 0.762 0.762)
					(thickness 0.2286)
				)
			)
		)
		(sheetname "05-GPS_IMU_SENSORS")
		(sheetfile "05-GPS_IMU_SENSORS.kicad_sch")
		(duplicate_pad_numbers_are_jumpers no)
		(pad "1" smd rect
			(at -0.7 0 90)
			(size 1.1 1.05)
			(layers "F.Cu" "F.Mask" "F.Paste")
			(net "GND")
		)
		(pad "2" smd rect
			(at 0.7 0 90)
			(size 1.1 1.05)
			(layers "F.Cu" "F.Mask" "F.Paste")
			(net "+3.3V")
		)
	)
	(footprint "Vault:MOLX-47589-0001_V"
		(layer "F.Cu")
		(at 228.1216 126.2412 90)
		(property "Reference" "J43"
			(at 15.123929 -0.16576 0)
			(unlocked yes)
			(layer "F.SilkS")
			(effects
				(font
					(size 0.762 0.762)
					(thickness 0.2032)
				)
			)
		)
		(property "Value" "47589-0001"
			(at -7.101071 4.9126 0)
			(unlocked yes)
			(layer "F.SilkS")
			(hide yes)
			(effects
				(font
					(size 0.762 0.762)
					(thickness 0.2032)
				)
			)
		)
		(sheetname "09-USBUart_PPSMUX_UARTMUX")
		(sheetfile "09-USBUart_PPSMUX_UARTMUX.kicad_sch")
		(duplicate_pad_numbers_are_jumpers no)
		(fp_line
			(start 3.75 -1.35)
			(end 3.75 0.15)
			(stroke
				(width 0.2)
				(type solid)
			)
			(layer "F.SilkS")
		)
		(fp_line
			(start 3.2 -1.35)
			(end 3.75 -1.35)
			(stroke
				(width 0.2)
				(type solid)
			)
			(layer "F.SilkS")
		)
		(fp_line
			(start -3.75 -1.35)
			(end -3.2 -1.35)
			(stroke
				(width 0.2)
				(type solid)
			)
			(layer "F.SilkS")
		)
		(fp_line
			(start -3.75 -1.35)
			(end -3.75 0.15)
			(stroke
				(width 0.2)
				(type solid)
			)
			(layer "F.SilkS")
		)
		(fp_line
			(start 3.75 2.85)
			(end 3.75 4.25)
			(stroke
				(width 0.2)
				(type solid)
			)
			(layer "F.SilkS")
		)
		(fp_line
			(start -3.75 2.85)
			(end -3.75 4.25)
			(stroke
				(width 0.2)
				(type solid)
			)
			(layer "F.SilkS")
		)
		(fp_line
			(start -3.75 4.25)
			(end 3.75 4.25)
			(stroke
				(width 0.2)
				(type solid)
			)
			(layer "F.SilkS")
		)
		(fp_circle
			(center -1.3 -2.4)
			(end -1.175 -2.4)
			(stroke
				(width 0.25)
				(type solid)
			)
			(fill no)
			(layer "F.SilkS")
		)
		(pad "1" smd rect
			(at -1.3 -1.175 270)
			(size 0.4 1.35)
			(layers "F.Cu" "F.Mask" "F.Paste")
			(net "USB_VBUS")
		)
		(pad "2" smd rect
			(at -0.65 -1.175 270)
			(size 0.4 1.35)
			(layers "F.Cu" "F.Mask" "F.Paste")
			(net "FTDI_USB_R_N")
		)
		(pad "3" smd rect
			(at 0 -1.175 90)
			(size 0.4 1.35)
			(layers "F.Cu" "F.Mask" "F.Paste")
			(net "FTDI_USB_R_P")
		)
		(pad "4" smd rect
			(at 0.65 -1.175 90)
			(size 0.4 1.35)
			(layers "F.Cu" "F.Mask" "F.Paste")
		)
		(pad "5" smd rect
			(at 1.3 -1.175 90)
			(size 0.4 1.35)
			(layers "F.Cu" "F.Mask" "F.Paste")
			(net "GND")
		)
		(pad "6" thru_hole oval
			(at -2.225 -1.5 180)
			(size 1.25 1.05)
			(drill oval 0.85 0.65)
			(layers "*.Cu" "*.Mask")
			(remove_unused_layers no)
			(net "GND")
		)
		(pad "7" thru_hole oval
			(at 2.225 -1.5 180)
			(size 1.25 1.05)
			(drill oval 0.85 0.65)
			(layers "*.Cu" "*.Mask")
			(remove_unused_layers no)
			(net "GND")
		)
		(pad "8" thru_hole oval
			(at -4.175 1.5 180)
			(size 1.9 1.2)
			(drill oval 1.3 0.6)
			(layers "*.Cu" "*.Mask")
			(remove_unused_layers no)
			(net "GND")
		)
		(pad "9" smd rect
			(at -1.15 1.5 90)
			(size 1.8 1.9)
			(layers "F.Cu" "F.Mask" "F.Paste")
			(net "GND")
		)
		(pad "10" smd rect
			(at 1.15 1.5 270)
			(size 1.8 1.9)
			(layers "F.Cu" "F.Mask" "F.Paste")
			(net "GND")
		)
		(pad "11" thru_hole oval
			(at 4.175 1.5 180)
			(size 1.9 1.2)
			(drill oval 1.3 0.6)
			(layers "*.Cu" "*.Mask")
			(remove_unused_layers no)
			(net "GND")
		)
	)
	(footprint "Passives:SOT65P210X110-3N"
		(layer "F.Cu")
		(at 212.3666 145.56546)
		(property "Reference" "D7"
			(at -0.345 -1.355915 0)
			(unlocked yes)
			(layer "F.SilkS")
			(effects
				(font
					(size 0.762 0.762)
					(thickness 0.2286)
				)
				(justify left bottom)
			)
		)
		(property "Value" "BAT54SW"
			(at 5.35585 -2.652805 0)
			(unlocked yes)
			(layer "F.SilkS")
			(hide yes)
			(effects
				(font
					(size 0.762 0.762)
					(thickness 0.2286)
				)
				(justify left bottom)
			)
		)
		(sheetname "04-PCIe_JTAG")
		(sheetfile "04-PCIe_JTAG.kicad_sch")
		(duplicate_pad_numbers_are_jumpers no)
		(fp_line
			(start -0.325 -1.1)
			(end 0.675 -1.1)
			(stroke
				(width 0.2)
				(type solid)
			)
			(layer "F.SilkS")
		)
		(fp_line
			(start -0.325 1.1)
			(end 0.675 1.1)
			(stroke
				(width 0.2)
				(type solid)
			)
			(layer "F.SilkS")
		)
		(fp_line
			(start 0.675 -0.65)
			(end 0.675 -1.1)
			(stroke
				(width 0.2)
				(type solid)
			)
			(layer "F.SilkS")
		)
		(fp_line
			(start 0.675 1.1)
			(end 0.675 0.65)
			(stroke
				(width 0.2)
				(type solid)
			)
			(layer "F.SilkS")
		)
		(fp_circle
			(center -1.125 -1.45)
			(end -1.125 -1.575)
			(stroke
				(width 0.25)
				(type solid)
			)
			(fill no)
			(layer "F.SilkS")
		)
		(pad "1" smd rect
			(at -1.125 -0.65 90)
			(size 0.5 0.9)
			(layers "F.Cu" "F.Mask" "F.Paste")
			(net "GND")
		)
		(pad "2" smd rect
			(at -1.125 0.65 90)
			(size 0.5 0.9)
			(layers "F.Cu" "F.Mask" "F.Paste")
			(net "+3.3V")
		)
		(pad "3" smd rect
			(at 1.125 0 90)
			(size 0.5 0.9)
			(layers "F.Cu" "F.Mask" "F.Paste")
			(net "FPGA_TMS")
		)
	)
	(footprint "Vault:FP-CC0402-MFG"
		(layer "F.Cu")
		(at 224.0216 129.3162 180)
		(property "Reference" "C86"
			(at 2.3714 -0.026921 0)
			(unlocked yes)
			(layer "F.SilkS")
			(effects
				(font
					(size 0.762 0.762)
					(thickness 0.2286)
				)
			)
		)
		(property "Value" "10nF_50V_0402"
			(at -2.592551 9.22982 90)
			(unlocked yes)
			(layer "F.SilkS")
			(hide yes)
			(effects
				(font
					(size 0.762 0.762)
					(thickness 0.2286)
				)
			)
		)
		(sheetname "09-USBUart_PPSMUX_UARTMUX")
		(sheetfile "09-USBUart_PPSMUX_UARTMUX.kicad_sch")
		(duplicate_pad_numbers_are_jumpers no)
		(fp_line
			(start 0.525 -0.675)
			(end -0.525 -0.675)
			(stroke
				(width 0.2)
				(type solid)
			)
			(layer "F.SilkS")
		)
		(fp_line
			(start 0.51967 0.68067)
			(end -0.53033 0.68067)
			(stroke
				(width 0.2)
				(type solid)
			)
			(layer "F.SilkS")
		)
		(fp_line
			(start 0.875 0.475)
			(end -0.875 0.475)
			(stroke
				(width 0.2)
				(type solid)
			)
			(layer "F.CrtYd")
		)
		(fp_line
			(start 0.875 -0.475)
			(end 0.875 0.475)
			(stroke
				(width 0.2)
				(type solid)
			)
			(layer "F.CrtYd")
		)
		(fp_line
			(start 0.875 -0.475)
			(end -0.875 -0.475)
			(stroke
				(width 0.2)
				(type solid)
			)
			(layer "F.CrtYd")
		)
		(fp_line
			(start -0.875 -0.475)
			(end -0.875 0.475)
			(stroke
				(width 0.2)
				(type solid)
			)
			(layer "F.CrtYd")
		)
		(fp_line
			(start 0.875 0.475)
			(end -0.875 0.475)
			(stroke
				(width 0.2)
				(type solid)
			)
			(layer "F.Fab")
		)
		(fp_line
			(start 0.875 -0.475)
			(end 0.875 0.475)
			(stroke
				(width 0.2)
				(type solid)
			)
			(layer "F.Fab")
		)
		(fp_line
			(start 0.875 -0.475)
			(end -0.875 -0.475)
			(stroke
				(width 0.2)
				(type solid)
			)
			(layer "F.Fab")
		)
		(fp_line
			(start 0.5 0)
			(end -0.5 0)
			(stroke
				(width 0.1)
				(type solid)
			)
			(layer "F.Fab")
		)
		(fp_line
			(start 0 -0.5)
			(end 0 0.5)
			(stroke
				(width 0.1)
				(type solid)
			)
			(layer "F.Fab")
		)
		(fp_line
			(start -0.875 -0.475)
			(end -0.875 0.475)
			(stroke
				(width 0.2)
				(type solid)
			)
			(layer "F.Fab")
		)
		(fp_text user "${REFERENCE}"
			(at -0.00001 0.09601 180)
			(unlocked yes)
			(layer "F.Fab")
			(effects
				(font
					(face "Arial")
					(size 0.63 0.63)
					(thickness 0.1)
				)
				(justify left bottom)
			)
		)
		(pad "1" smd rect
			(at -0.5 0 180)
			(size 0.5 0.5)
			(layers "F.Cu" "F.Mask" "F.Paste")
			(net "USB_VBUS")
			(solder_mask_margin 0)
			(solder_paste_margin 0)
		)
		(pad "2" smd rect
			(at 0.5 0 180)
			(size 0.5 0.5)
			(layers "F.Cu" "F.Mask" "F.Paste")
			(net "GND")
			(solder_mask_margin 0)
			(solder_paste_margin 0)
		)
	)
	(footprint "Vault:RESC1005X40X25NL05T05"
		(layer "F.Cu")
		(at 225.1466 116.8162)
		(property "Reference" "R43"
			(at -3.4964 0.226931 0)
			(unlocked yes)
			(layer "F.SilkS")
			(effects
				(font
					(size 0.762 0.762)
					(thickness 0.2286)
				)
			)
		)
		(property "Value" "27_1%_0402"
			(at -3.011631 6.10665 270)
			(unlocked yes)
			(layer "F.SilkS")
			(hide yes)
			(effects
				(font
					(size 0.762 0.762)
					(thickness 0.2286)
				)
			)
		)
		(sheetname "09-USBUart_PPSMUX_UARTMUX")
		(sheetfile "09-USBUart_PPSMUX_UARTMUX.kicad_sch")
		(duplicate_pad_numbers_are_jumpers no)
		(pad "1" smd rect
			(at -0.45 0 90)
			(size 0.55 0.55)
			(layers "F.Cu" "F.Mask" "F.Paste")
			(net "FTDI_USB_R_N")
		)
		(pad "2" smd rect
			(at 0.45 0 90)
			(size 0.55 0.55)
			(layers "F.Cu" "F.Mask" "F.Paste")
			(net "FTDI_USB_N")
		)
	)
	(footprint "Vault:FP-LTST-C191KGKT-MFG"
		(layer "F.Cu")
		(at 224.7216 111.1162)
		(property "Reference" "D24"
			(at -3.4714 -0.073079 0)
			(unlocked yes)
			(layer "F.SilkS")
			(effects
				(font
					(size 0.762 0.762)
					(thickness 0.2286)
				)
			)
		)
		(property "Value" "LTST-C191KGKT"
			(at -3.519671 10.67713 270)
			(unlocked yes)
			(layer "F.SilkS")
			(hide yes)
			(effects
				(font
					(size 0.762 0.762)
					(thickness 0.2286)
				)
			)
		)
		(sheetname "08-DIPSwitches_I2C")
		(sheetfile "08-DIPSwitches_I2C.kicad_sch")
		(duplicate_pad_numbers_are_jumpers no)
		(fp_line
			(start -0.85 -0.775)
			(end 0.85 -0.775)
			(stroke
				(width 0.2)
				(type solid)
			)
			(layer "F.SilkS")
		)
		(fp_line
			(start -0.85 0.775)
			(end 0.85 0.775)
			(stroke
				(width 0.2)
				(type solid)
			)
			(layer "F.SilkS")
		)
		(fp_circle
			(center -1.7 0)
			(end -1.7 -0.125)
			(stroke
				(width 0.25)
				(type solid)
			)
			(fill no)
			(layer "F.SilkS")
		)
		(fp_line
			(start -1.25 -0.55)
			(end 1.25 -0.55)
			(stroke
				(width 0.2)
				(type solid)
			)
			(layer "F.CrtYd")
		)
		(fp_line
			(start -1.25 0.55)
			(end -1.25 -0.55)
			(stroke
				(width 0.2)
				(type solid)
			)
			(layer "F.CrtYd")
		)
		(fp_line
			(start -1.25 0.55)
			(end 1.25 0.55)
			(stroke
				(width 0.2)
				(type solid)
			)
			(layer "F.CrtYd")
		)
		(fp_line
			(start 1.25 0.55)
			(end 1.25 -0.55)
			(stroke
				(width 0.2)
				(type solid)
			)
			(layer "F.CrtYd")
		)
		(fp_line
			(start -1.25 -0.55)
			(end 1.25 -0.55)
			(stroke
				(width 0.2)
				(type solid)
			)
			(layer "F.Fab")
		)
		(fp_line
			(start -1.25 0.55)
			(end -1.25 -0.55)
			(stroke
				(width 0.2)
				(type solid)
			)
			(layer "F.Fab")
		)
		(fp_line
			(start -1.25 0.55)
			(end 1.25 0.55)
			(stroke
				(width 0.2)
				(type solid)
			)
			(layer "F.Fab")
		)
		(fp_line
			(start -0.5 0)
			(end 0.5 0)
			(stroke
				(width 0.1)
				(type solid)
			)
			(layer "F.Fab")
		)
		(fp_line
			(start 0 0.5)
			(end 0 -0.5)
			(stroke
				(width 0.1)
				(type solid)
			)
			(layer "F.Fab")
		)
		(fp_line
			(start 1.25 0.55)
			(end 1.25 -0.55)
			(stroke
				(width 0.2)
				(type solid)
			)
			(layer "F.Fab")
		)
		(fp_text user "${REFERENCE}"
			(at 0 0.29534 360)
			(unlocked yes)
			(layer "F.Fab")
			(effects
				(font
					(face "Arial")
					(size 0.63 0.63)
					(thickness 0.1)
				)
				(justify left bottom)
			)
		)
		(pad "1" smd rect
			(at -0.75 0)
			(size 0.8 0.8)
			(layers "F.Cu" "F.Mask" "F.Paste")
			(net "NetD24_1")
			(solder_mask_margin 0)
			(solder_paste_margin 0)
		)
		(pad "2" smd rect
			(at 0.75 0)
			(size 0.8 0.8)
			(layers "F.Cu" "F.Mask" "F.Paste")
			(net "+3.3V")
			(solder_mask_margin 0)
			(solder_paste_margin 0)
		)
	)
	(footprint ""
		(layer "F.Cu")
		(at 162.04661 65.0162)
		(property "Reference" ""
			(at 0 0 0)
			(layer "F.SilkS")
			(effects
				(font
					(size 1.27 1.27)
				)
			)
		)
		(property "Value" ""
			(at 0 0 0)
			(layer "F.Fab")
			(effects
				(font
					(size 1.27 1.27)
				)
			)
		)
		(duplicate_pad_numbers_are_jumpers no)
		(pad "2" thru_hole circle
			(at 0 0)
			(size 6.5 6.5)
			(drill 4.2)
			(layers "*.Cu" "*.Mask")
			(remove_unused_layers no)
			(net "GND")
			(thermal_bridge_angle 90)
		)
	)
	(footprint "Vault:RESC1005X40X25NL05T05"
		(layer "F.Cu")
		(at 197.6216 132.2162)
		(property "Reference" "R160"
			(at 0.3032 -0.873069 0)
			(unlocked yes)
			(layer "F.SilkS")
			(effects
				(font
					(size 0.762 0.762)
					(thickness 0.2032)
				)
			)
		)
		(property "Value" "DNI_27_1%_0402"
			(at -2.732271 10.270975 270)
			(unlocked yes)
			(layer "F.SilkS")
			(hide yes)
			(effects
				(font
					(size 0.762 0.762)
					(thickness 0.2032)
				)
			)
		)
		(sheetname "11-M2_RCB_MUX")
		(sheetfile "11-M2_RCB_MUX.kicad_sch")
		(duplicate_pad_numbers_are_jumpers no)
		(pad "1" smd rect
			(at -0.45 0 90)
			(size 0.55 0.55)
			(layers "F.Cu" "F.Mask" "F.Paste")
			(net "M2_GPS2_TP2")
		)
		(pad "2" smd rect
			(at 0.45 0 90)
			(size 0.55 0.55)
			(layers "F.Cu" "F.Mask" "F.Paste")
			(net "GPS2_TP2")
		)
	)
	(footprint "Vault:FP-T495D107K016ATE125-MFG"
		(layer "F.Cu")
		(at 188.3216 81.0162 -90)
		(property "Reference" "C75"
			(at 0.9286 -3.273069 270)
			(unlocked yes)
			(layer "F.SilkS")
			(effects
				(font
					(size 0.762 0.762)
					(thickness 0.2286)
				)
			)
		)
		(property "Value" "100uF_16V_2917"
			(at -5.818351 8.010455 180)
			(unlocked yes)
			(layer "F.SilkS")
			(hide yes)
			(effects
				(font
					(size 0.762 0.762)
					(thickness 0.2286)
				)
			)
		)
		(sheetname "03-POWER")
		(sheetfile "03-POWER.kicad_sch")
		(duplicate_pad_numbers_are_jumpers no)
		(fp_line
			(start -3.8 2.3)
			(end -3.8 1.54)
			(stroke
				(width 0.2)
				(type solid)
			)
			(layer "F.SilkS")
		)
		(fp_line
			(start 3.8 2.3)
			(end -3.8 2.3)
			(stroke
				(width 0.2)
				(type solid)
			)
			(layer "F.SilkS")
		)
		(fp_line
			(start 3.8 2.3)
			(end 3.8 1.54)
			(stroke
				(width 0.2)
				(type solid)
			)
			(layer "F.SilkS")
		)
		(fp_line
			(start 4.7 0.3)
			(end 4.7 -0.3)
			(stroke
				(width 0.2)
				(type solid)
			)
			(layer "F.SilkS")
		)
		(fp_line
			(start 5 0)
			(end 4.4 0)
			(stroke
				(width 0.2)
				(type solid)
			)
			(layer "F.SilkS")
		)
		(fp_line
			(start -3.8 -1.54)
			(end -3.8 -2.3)
			(stroke
				(width 0.2)
				(type solid)
			)
			(layer "F.SilkS")
		)
		(fp_line
			(start 3.8 -1.54)
			(end 3.8 -2.3)
			(stroke
				(width 0.2)
				(type solid)
			)
			(layer "F.SilkS")
		)
		(fp_line
			(start 3.8 -2.3)
			(end -3.8 -2.3)
			(stroke
				(width 0.2)
				(type solid)
			)
			(layer "F.SilkS")
		)
		(fp_line
			(start -4.105 2.4)
			(end -4.105 -2.4)
			(stroke
				(width 0.2)
				(type solid)
			)
			(layer "F.CrtYd")
		)
		(fp_line
			(start 4.105 2.4)
			(end -4.105 2.4)
			(stroke
				(width 0.2)
				(type solid)
			)
			(layer "F.CrtYd")
		)
		(fp_line
			(start 4.105 2.4)
			(end 4.105 -2.4)
			(stroke
				(width 0.2)
				(type solid)
			)
			(layer "F.CrtYd")
		)
		(fp_line
			(start 4.105 -2.4)
			(end -4.105 -2.4)
			(stroke
				(width 0.2)
				(type solid)
			)
			(layer "F.CrtYd")
		)
		(fp_line
			(start -4.105 2.4)
			(end -4.105 -2.4)
			(stroke
				(width 0.2)
				(type solid)
			)
			(layer "F.Fab")
		)
		(fp_line
			(start 4.105 2.4)
			(end -4.105 2.4)
			(stroke
				(width 0.2)
				(type solid)
			)
			(layer "F.Fab")
		)
		(fp_line
			(start 4.105 2.4)
			(end 4.105 -2.4)
			(stroke
				(width 0.2)
				(type solid)
			)
			(layer "F.Fab")
		)
		(fp_line
			(start 0 0.5)
			(end 0 -0.5)
			(stroke
				(width 0.1)
				(type solid)
			)
			(layer "F.Fab")
		)
		(fp_line
			(start 0.5 0)
			(end -0.5 0)
			(stroke
				(width 0.1)
				(type solid)
			)
			(layer "F.Fab")
		)
		(fp_line
			(start 4.105 -2.4)
			(end -4.105 -2.4)
			(stroke
				(width 0.2)
				(type solid)
			)
			(layer "F.Fab")
		)
		(fp_text user "${REFERENCE}"
			(at 0 0.28425 270)
			(unlocked yes)
			(layer "F.Fab")
			(effects
				(font
					(face "Arial")
					(size 0.63 0.63)
					(thickness 0.1)
				)
				(justify left bottom)
			)
		)
		(pad "1" smd rect
			(at -3.01 0 270)
			(size 1.99 2.33)
			(layers "F.Cu" "F.Mask" "F.Paste")
			(net "GND")
			(solder_mask_margin 0)
			(solder_paste_margin 0)
		)
		(pad "2" smd rect
			(at 3.01 0 270)
			(size 1.99 2.33)
			(layers "F.Cu" "F.Mask" "F.Paste")
			(net "+12V")
			(solder_mask_margin 0)
			(solder_paste_margin 0)
		)
	)
)
